(kicad_pcb
	(version 20260206)
	(generator "pcbnew")
	(generator_version "10.0")
	(general
		(thickness 1.6)
		(legacy_teardrops no)
	)
	(paper "A4")
	(title_block
		(title "dpb — 14545-sa.0730WZS0815.brd")
		(comment 1 "Honey Badger (Wiwynn) / footprints 608-612 of 1066")
	)
	(layers
		(0 "F.Cu" signal "TOP")
		(4 "In1.Cu" signal "L2GND")
		(6 "In2.Cu" signal "L3")
		(8 "In3.Cu" signal "L4VCC")
		(10 "In4.Cu" signal "L5VCC")
		(12 "In5.Cu" signal "L6")
		(14 "In6.Cu" signal "L7GND")
		(2 "B.Cu" signal "BOTTOM")
		(9 "F.Adhes" user "F.Adhesive")
		(11 "B.Adhes" user "B.Adhesive")
		(13 "F.Paste" user "Package Geometry/Pastemask Top")
		(15 "B.Paste" user "Package Geometry/Pastemask Bottom")
		(5 "F.SilkS" user "Ref Des/Silkscreen Top")
		(7 "B.SilkS" user "Ref Des/Silkscreen Bottom")
		(1 "F.Mask" user "Board Geometry/Soldermask Top")
		(3 "B.Mask" user "Board Geometry/Soldermask Bottom")
		(17 "Dwgs.User" user "User.Drawings")
		(19 "Cmts.User" user "User.Comments")
		(21 "Eco1.User" user "User.Eco1")
		(23 "Eco2.User" user "User.Eco2")
		(25 "Edge.Cuts" user "Board Geometry/Outline")
		(27 "Margin" user)
		(31 "F.CrtYd" user "Package Geometry/Place Bound Top")
		(29 "B.CrtYd" user "Package Geometry/Place Bound Bottom")
		(35 "F.Fab" user "Ref Des/Assembly Top")
		(33 "B.Fab" user "Ref Des/Assembly Bottom")
	)
	(footprint ""
		(layer "F.Cu")
		(at 17.855946 -165.5826 90)
		(property "Reference" "Q47"
			(at 0 0 90)
			(layer "F.SilkS")
			(hide yes)
			(effects
				(font
					(size 1.27 1.27)
				)
			)
		)
		(property "Value" "PMBS3904-1-GP"
			(at 0 -9.0932 90)
			(unlocked yes)
			(layer "F.Fab")
			(hide yes)
			(effects
				(font
					(size 1.016 1.016)
					(thickness 0.1524)
				)
			)
		)
		(property "Device Type" "SOT-23-10H44"
			(at 0 -10.6172 90)
			(unlocked yes)
			(layer "F.Fab")
			(hide yes)
			(effects
				(font
					(size 1.016 1.016)
					(thickness 0.1524)
				)
			)
		)
		(duplicate_pad_numbers_are_jumpers no)
		(fp_line
			(start 1.651 -1.778)
			(end -1.651 -1.778)
			(stroke
				(width 0.1524)
				(type default)
			)
			(layer "F.SilkS")
		)
		(fp_line
			(start -1.651 -1.778)
			(end -1.651 1.778)
			(stroke
				(width 0.1524)
				(type default)
			)
			(layer "F.SilkS")
		)
		(fp_line
			(start 1.651 1.778)
			(end 1.651 -1.778)
			(stroke
				(width 0.1524)
				(type default)
			)
			(layer "F.SilkS")
		)
		(fp_line
			(start -1.651 1.778)
			(end 1.651 1.778)
			(stroke
				(width 0.1524)
				(type default)
			)
			(layer "F.SilkS")
		)
		(fp_line
			(start -0.9906 1.86309)
			(end -0.701294 2.15265)
			(stroke
				(width 0.0127)
				(type default)
			)
			(layer "F.SilkS")
		)
		(fp_line
			(start -0.994156 1.8669)
			(end -0.987044 1.8669)
			(stroke
				(width 0.0127)
				(type default)
			)
			(layer "F.SilkS")
		)
		(fp_line
			(start -1.003808 1.876552)
			(end -0.977646 1.876552)
			(stroke
				(width 0.0127)
				(type default)
			)
			(layer "F.SilkS")
		)
		(fp_line
			(start -0.635 1.8796)
			(end -1.7526 1.8796)
			(stroke
				(width 0.3302)
				(type default)
			)
			(layer "F.SilkS")
		)
		(fp_line
			(start -1.7526 1.8796)
			(end -1.7526 0.9906)
			(stroke
				(width 0.3302)
				(type default)
			)
			(layer "F.SilkS")
		)
		(fp_line
			(start -1.013206 1.88595)
			(end -0.967994 1.88595)
			(stroke
				(width 0.0127)
				(type default)
			)
			(layer "F.SilkS")
		)
		(fp_line
			(start -1.022858 1.895602)
			(end -0.958596 1.895602)
			(stroke
				(width 0.0127)
				(type default)
			)
			(layer "F.SilkS")
		)
		(fp_line
			(start -1.032256 1.905)
			(end -0.948944 1.905)
			(stroke
				(width 0.0127)
				(type default)
			)
			(layer "F.SilkS")
		)
		(fp_line
			(start -1.041908 1.914652)
			(end -0.939546 1.914652)
			(stroke
				(width 0.0127)
				(type default)
			)
			(layer "F.SilkS")
		)
		(fp_line
			(start -1.051306 1.92405)
			(end -0.929894 1.92405)
			(stroke
				(width 0.0127)
				(type default)
			)
			(layer "F.SilkS")
		)
		(fp_line
			(start -1.060958 1.933702)
			(end -0.920496 1.933702)
			(stroke
				(width 0.0127)
				(type default)
			)
			(layer "F.SilkS")
		)
		(fp_line
			(start -1.070356 1.9431)
			(end -0.910844 1.9431)
			(stroke
				(width 0.0127)
				(type default)
			)
			(layer "F.SilkS")
		)
		(fp_line
			(start -1.080008 1.952752)
			(end -0.901446 1.952752)
			(stroke
				(width 0.0127)
				(type default)
			)
			(layer "F.SilkS")
		)
		(fp_line
			(start -1.089406 1.96215)
			(end -0.891794 1.96215)
			(stroke
				(width 0.0127)
				(type default)
			)
			(layer "F.SilkS")
		)
		(fp_line
			(start -1.099058 1.971802)
			(end -0.882396 1.971802)
			(stroke
				(width 0.0127)
				(type default)
			)
			(layer "F.SilkS")
		)
		(fp_line
			(start -1.108456 1.9812)
			(end -0.872744 1.9812)
			(stroke
				(width 0.0127)
				(type default)
			)
			(layer "F.SilkS")
		)
		(fp_line
			(start -1.118108 1.990852)
			(end -0.863346 1.990852)
			(stroke
				(width 0.0127)
				(type default)
			)
			(layer "F.SilkS")
		)
		(fp_line
			(start -1.127506 2.00025)
			(end -0.853694 2.00025)
			(stroke
				(width 0.0127)
				(type default)
			)
			(layer "F.SilkS")
		)
		(fp_line
			(start -1.137158 2.009902)
			(end -0.844296 2.009902)
			(stroke
				(width 0.0127)
				(type default)
			)
			(layer "F.SilkS")
		)
		(fp_line
			(start -1.146556 2.0193)
			(end -0.834644 2.0193)
			(stroke
				(width 0.0127)
				(type default)
			)
			(layer "F.SilkS")
		)
		(fp_line
			(start -1.156208 2.028952)
			(end -0.825246 2.028952)
			(stroke
				(width 0.0127)
				(type default)
			)
			(layer "F.SilkS")
		)
		(fp_line
			(start -1.165606 2.03835)
			(end -0.815594 2.03835)
			(stroke
				(width 0.0127)
				(type default)
			)
			(layer "F.SilkS")
		)
		(fp_line
			(start -1.175258 2.048002)
			(end -0.806196 2.048002)
			(stroke
				(width 0.0127)
				(type default)
			)
			(layer "F.SilkS")
		)
		(fp_line
			(start -1.184656 2.0574)
			(end -0.796544 2.0574)
			(stroke
				(width 0.0127)
				(type default)
			)
			(layer "F.SilkS")
		)
		(fp_line
			(start -1.194308 2.067052)
			(end -0.787146 2.067052)
			(stroke
				(width 0.0127)
				(type default)
			)
			(layer "F.SilkS")
		)
		(fp_line
			(start -1.203706 2.07645)
			(end -0.777494 2.07645)
			(stroke
				(width 0.0127)
				(type default)
			)
			(layer "F.SilkS")
		)
		(fp_line
			(start -1.213358 2.086102)
			(end -0.768096 2.086102)
			(stroke
				(width 0.0127)
				(type default)
			)
			(layer "F.SilkS")
		)
		(fp_line
			(start -1.222756 2.0955)
			(end -0.758444 2.0955)
			(stroke
				(width 0.0127)
				(type default)
			)
			(layer "F.SilkS")
		)
		(fp_line
			(start -1.232408 2.105152)
			(end -0.749046 2.105152)
			(stroke
				(width 0.0127)
				(type default)
			)
			(layer "F.SilkS")
		)
		(fp_line
			(start -1.241806 2.11455)
			(end -0.739394 2.11455)
			(stroke
				(width 0.0127)
				(type default)
			)
			(layer "F.SilkS")
		)
		(fp_line
			(start -1.251458 2.124202)
			(end -0.729996 2.124202)
			(stroke
				(width 0.0127)
				(type default)
			)
			(layer "F.SilkS")
		)
		(fp_line
			(start -1.260856 2.1336)
			(end -0.720344 2.1336)
			(stroke
				(width 0.0127)
				(type default)
			)
			(layer "F.SilkS")
		)
		(fp_line
			(start -0.719074 2.145538)
			(end -1.265936 2.14122)
			(stroke
				(width 0.0127)
				(type default)
			)
			(layer "F.SilkS")
		)
		(fp_line
			(start -1.279398 2.152142)
			(end -0.9906 1.86309)
			(stroke
				(width 0.0127)
				(type default)
			)
			(layer "F.SilkS")
		)
		(fp_line
			(start -0.71628 2.15265)
			(end -1.26492 2.15265)
			(stroke
				(width 0.0127)
				(type default)
			)
			(layer "F.SilkS")
		)
		(fp_line
			(start -1.279144 2.15265)
			(end -0.701294 2.15265)
			(stroke
				(width 0.0127)
				(type default)
			)
			(layer "F.SilkS")
		)
		(fp_poly
			(pts
				(xy -1.285748 2.159) (xy -1.285748 1.8796) (xy -1.778 1.8796) (xy -1.778 -1.8796) (xy 1.778 -1.8796)
				(xy 1.778 1.8796) (xy -0.694944 1.8796) (xy -0.694944 2.159)
			)
			(stroke
				(width 0)
				(type default)
			)
			(fill no)
			(layer "F.CrtYd")
		)
		(fp_poly
			(pts
				(xy -1.285748 2.159) (xy -1.285748 1.8796) (xy -1.778 1.8796) (xy -1.778 -1.8796) (xy 1.778 -1.8796)
				(xy 1.778 1.8796) (xy -0.694944 1.8796) (xy -0.694944 2.159)
			)
			(stroke
				(width 0)
				(type default)
			)
			(fill no)
			(layer "F.Fab")
		)
		(pad "1" smd rect
			(at -0.98425 0.9525 90)
			(size 0.762 1.143)
			(layers "F.Cu" "F.Mask" "F.Paste")
			(net "FLT_HDD13_B")
		)
		(pad "2" smd rect
			(at 0.98425 0.9525 90)
			(size 0.762 1.143)
			(layers "F.Cu" "F.Mask" "F.Paste")
			(net "GND")
		)
		(pad "3" smd rect
			(at 0 -0.9525 90)
			(size 0.762 1.143)
			(layers "F.Cu" "F.Mask" "F.Paste")
			(net "DRIVE_ACT_13")
		)
	)
	(footprint ""
		(layer "F.Cu")
		(at 46.481746 -24.1427 -90)
		(property "Reference" "PR24"
			(at 0 0 270)
			(layer "F.SilkS")
			(hide yes)
			(effects
				(font
					(size 1.27 1.27)
				)
			)
		)
		(property "Value" "0R3J-0-U-GP"
			(at -0.0254 -2.5146 270)
			(unlocked yes)
			(layer "F.Fab")
			(hide yes)
			(effects
				(font
					(size 1.016 1.016)
					(thickness 0.1524)
				)
			)
		)
		(property "Device Type" "R603H22"
			(at -0.0254 -4.0386 270)
			(unlocked yes)
			(layer "F.Fab")
			(hide yes)
			(effects
				(font
					(size 1.016 1.016)
					(thickness 0.1524)
				)
			)
		)
		(duplicate_pad_numbers_are_jumpers no)
		(fp_line
			(start -0.4826 0)
			(end -0.2032 0)
			(stroke
				(width 0.2032)
				(type default)
			)
			(layer "F.SilkS")
		)
		(fp_line
			(start 0.2032 0)
			(end 0.4826 0)
			(stroke
				(width 0.2032)
				(type default)
			)
			(layer "F.SilkS")
		)
		(fp_rect
			(start -0.5842 1.3335)
			(end 0.5842 -1.3335)
			(stroke
				(width 0)
				(type default)
			)
			(fill no)
			(layer "F.CrtYd")
		)
		(fp_rect
			(start -0.5842 1.3335)
			(end 0.5842 -1.3335)
			(stroke
				(width 0)
				(type default)
			)
			(fill no)
			(layer "F.Fab")
		)
		(pad "1" smd custom
			(at 0 -0.762 270)
			(size 0.2159 0.2159)
			(layers "F.Cu" "F.Mask" "F.Paste")
			(net "P5VB_VBST")
			(options
				(clearance outline)
				(anchor circle)
			)
			(primitives
				(gr_poly
					(pts
						(arc
							(start -0.3302 -0.4318)
							(mid -0.402042 -0.402042)
							(end -0.4318 -0.3302)
						)
						(arc
							(start -0.4318 0.3302)
							(mid -0.402042 0.402042)
							(end -0.3302 0.4318)
						)
						(arc
							(start 0.3302 0.4318)
							(mid 0.402042 0.402042)
							(end 0.4318 0.3302)
						)
						(arc
							(start 0.4318 -0.3302)
							(mid 0.402042 -0.402042)
							(end 0.3302 -0.4318)
						)
					)
					(width 0)
					(fill yes)
				)
			)
		)
		(pad "2" smd custom
			(at 0 0.762 270)
			(size 0.2159 0.2159)
			(layers "F.Cu" "F.Mask" "F.Paste")
			(net "P5VB_VBST_NET")
			(options
				(clearance outline)
				(anchor circle)
			)
			(primitives
				(gr_poly
					(pts
						(arc
							(start -0.3302 -0.4318)
							(mid -0.402042 -0.402042)
							(end -0.4318 -0.3302)
						)
						(arc
							(start -0.4318 0.3302)
							(mid -0.402042 0.402042)
							(end -0.3302 0.4318)
						)
						(arc
							(start 0.3302 0.4318)
							(mid 0.402042 0.402042)
							(end 0.4318 0.3302)
						)
						(arc
							(start 0.4318 -0.3302)
							(mid 0.402042 -0.402042)
							(end 0.3302 -0.4318)
						)
					)
					(width 0)
					(fill yes)
				)
			)
		)
	)
	(footprint ""
		(layer "F.Cu")
		(at 55.498746 -183.4007 180)
		(property "Reference" "C236"
			(at 0 0 180)
			(layer "F.SilkS")
			(hide yes)
			(effects
				(font
					(size 1.27 1.27)
				)
			)
		)
		(property "Value" "SC1U16V3KX-5GP"
			(at 0 -2.8194 180)
			(unlocked yes)
			(layer "F.Fab")
			(hide yes)
			(effects
				(font
					(size 1.016 1.016)
					(thickness 0.1524)
				)
			)
		)
		(property "Device Type" "C603H36"
			(at 0 -4.3434 180)
			(unlocked yes)
			(layer "F.Fab")
			(hide yes)
			(effects
				(font
					(size 1.016 1.016)
					(thickness 0.1524)
				)
			)
		)
		(duplicate_pad_numbers_are_jumpers no)
		(fp_line
			(start 0.508 0)
			(end -0.508 0)
			(stroke
				(width 0.2032)
				(type default)
			)
			(layer "F.SilkS")
		)
		(fp_rect
			(start -0.5842 1.3335)
			(end 0.5842 -1.3335)
			(stroke
				(width 0)
				(type default)
			)
			(fill no)
			(layer "F.CrtYd")
		)
		(fp_rect
			(start -0.5842 1.3335)
			(end 0.5842 -1.3335)
			(stroke
				(width 0)
				(type default)
			)
			(fill no)
			(layer "F.Fab")
		)
		(pad "1" smd custom
			(at 0 -0.762 180)
			(size 0.2159 0.2159)
			(layers "F.Cu" "F.Mask" "F.Paste")
			(net "P5V_HDD8")
			(options
				(clearance outline)
				(anchor circle)
			)
			(primitives
				(gr_poly
					(pts
						(arc
							(start -0.3302 -0.4318)
							(mid -0.402042 -0.402042)
							(end -0.4318 -0.3302)
						)
						(arc
							(start -0.4318 0.3302)
							(mid -0.402042 0.402042)
							(end -0.3302 0.4318)
						)
						(arc
							(start 0.3302 0.4318)
							(mid 0.402042 0.402042)
							(end 0.4318 0.3302)
						)
						(arc
							(start 0.4318 -0.3302)
							(mid 0.402042 -0.402042)
							(end 0.3302 -0.4318)
						)
					)
					(width 0)
					(fill yes)
				)
			)
		)
		(pad "2" smd custom
			(at 0 0.762 180)
			(size 0.2159 0.2159)
			(layers "F.Cu" "F.Mask" "F.Paste")
			(net "GND")
			(options
				(clearance outline)
				(anchor circle)
			)
			(primitives
				(gr_poly
					(pts
						(arc
							(start -0.3302 -0.4318)
							(mid -0.402042 -0.402042)
							(end -0.4318 -0.3302)
						)
						(arc
							(start -0.4318 0.3302)
							(mid -0.402042 0.402042)
							(end -0.3302 0.4318)
						)
						(arc
							(start 0.3302 0.4318)
							(mid 0.402042 0.402042)
							(end 0.4318 0.3302)
						)
						(arc
							(start 0.4318 -0.3302)
							(mid 0.402042 -0.402042)
							(end 0.3302 -0.4318)
						)
					)
					(width 0)
					(fill yes)
				)
			)
		)
	)
	(footprint ""
		(layer "F.Cu")
		(at 26.55443 -242.948206 90)
		(property "Reference" "C294"
			(at 0 0 90)
			(layer "F.SilkS")
			(hide yes)
			(effects
				(font
					(size 1.27 1.27)
				)
			)
		)
		(property "Value" "SCD01U50V2KX-1GP"
			(at 1.1811 -2.7051 90)
			(unlocked yes)
			(layer "F.Fab")
			(hide yes)
			(effects
				(font
					(size 1.016 1.016)
					(thickness 0.1524)
				)
			)
		)
		(property "Device Type" "C402H22"
			(at 1.1811 -4.2291 90)
			(unlocked yes)
			(layer "F.Fab")
			(hide yes)
			(effects
				(font
					(size 1.016 1.016)
					(thickness 0.1524)
				)
			)
		)
		(duplicate_pad_numbers_are_jumpers no)
		(fp_rect
			(start -0.4318 0.9525)
			(end 0.4318 -0.9525)
			(stroke
				(width 0)
				(type default)
			)
			(fill no)
			(layer "F.CrtYd")
		)
		(fp_rect
			(start -0.4318 0.9525)
			(end 0.4318 -0.9525)
			(stroke
				(width 0)
				(type default)
			)
			(fill no)
			(layer "F.Fab")
		)
		(pad "1" smd custom
			(at 0 -0.4445 90)
			(size 0.1524 0.1524)
			(layers "F.Cu" "F.Mask" "F.Paste")
			(net "SAS2X28_DRIVE_RX_N_A12")
			(options
				(clearance outline)
				(anchor circle)
			)
			(primitives
				(gr_poly
					(pts
						(arc
							(start 0.3048 -0.2032)
							(mid 0.275042 -0.275042)
							(end 0.2032 -0.3048)
						)
						(arc
							(start -0.2032 -0.3048)
							(mid -0.275042 -0.275042)
							(end -0.3048 -0.2032)
						)
						(arc
							(start -0.3048 0.2032)
							(mid -0.275042 0.275042)
							(end -0.2032 0.3048)
						)
						(arc
							(start 0.2032 0.3048)
							(mid 0.275042 0.275042)
							(end 0.3048 0.2032)
						)
					)
					(width 0)
					(fill yes)
				)
			)
		)
		(pad "2" smd custom
			(at 0 0.4445 90)
			(size 0.1524 0.1524)
			(layers "F.Cu" "F.Mask" "F.Paste")
			(net "SAS2X28_A_HDD12_RX_-")
			(options
				(clearance outline)
				(anchor circle)
			)
			(primitives
				(gr_poly
					(pts
						(arc
							(start 0.3048 -0.2032)
							(mid 0.275042 -0.275042)
							(end 0.2032 -0.3048)
						)
						(arc
							(start -0.2032 -0.3048)
							(mid -0.275042 -0.275042)
							(end -0.3048 -0.2032)
						)
						(arc
							(start -0.3048 0.2032)
							(mid -0.275042 0.275042)
							(end -0.2032 0.3048)
						)
						(arc
							(start 0.2032 0.3048)
							(mid 0.275042 0.275042)
							(end 0.3048 0.2032)
						)
					)
					(width 0)
					(fill yes)
				)
			)
		)
	)
	(footprint ""
		(layer "F.Cu")
		(at 81.279746 -188.8617 -90)
		(property "Reference" "U27"
			(at 0 0 270)
			(layer "F.SilkS")
			(hide yes)
			(effects
				(font
					(size 1.27 1.27)
				)
			)
		)
		(property "Value" "74LVC1G08GW-1-GP"
			(at -2.3368 -8.6868 270)
			(unlocked yes)
			(layer "F.Fab")
			(hide yes)
			(effects
				(font
					(size 1.016 1.016)
					(thickness 0.1524)
				)
			)
		)
		(property "Device Type" "SC70-5H44"
			(at -2.3114 -10.414 270)
			(unlocked yes)
			(layer "F.Fab")
			(hide yes)
			(effects
				(font
					(size 1.016 1.016)
					(thickness 0.1524)
				)
			)
		)
		(duplicate_pad_numbers_are_jumpers no)
		(fp_line
			(start -1.27 1.7018)
			(end -1.27 -1.7018)
			(stroke
				(width 0.1524)
				(type default)
			)
			(layer "F.SilkS")
		)
		(fp_line
			(start 1.27 1.7018)
			(end -1.27 1.7018)
			(stroke
				(width 0.1524)
				(type default)
			)
			(layer "F.SilkS")
		)
		(fp_line
			(start -1.27 -1.7018)
			(end 1.27 -1.7018)
			(stroke
				(width 0.1524)
				(type default)
			)
			(layer "F.SilkS")
		)
		(fp_line
			(start 1.27 -1.7018)
			(end 1.27 1.7018)
			(stroke
				(width 0.1524)
				(type default)
			)
			(layer "F.SilkS")
		)
		(fp_line
			(start 0.6604 -1.8034)
			(end 1.3843 -1.8034)
			(stroke
				(width 0.3302)
				(type default)
			)
			(layer "F.SilkS")
		)
		(fp_line
			(start 1.3843 -1.8034)
			(end 1.3843 -1.1176)
			(stroke
				(width 0.3302)
				(type default)
			)
			(layer "F.SilkS")
		)
		(fp_rect
			(start -1.524 1.9558)
			(end 1.524 -1.9558)
			(stroke
				(width 0)
				(type default)
			)
			(fill no)
			(layer "F.CrtYd")
		)
		(fp_poly
			(pts
				(xy -1.524 -1.9558) (xy 1.524 -1.9558) (xy 1.524 1.9558) (xy -1.524 1.9558)
			)
			(stroke
				(width 0)
				(type default)
			)
			(fill no)
			(layer "F.Fab")
		)
		(pad "1" smd rect
			(at 0.65024 -0.8255 270)
			(size 0.4064 1.2192)
			(layers "F.Cu" "F.Mask" "F.Paste")
			(net "SAS_EXP_B_PWR8")
		)
		(pad "2" smd rect
			(at 0 -0.8255 270)
			(size 0.4064 1.2192)
			(layers "F.Cu" "F.Mask" "F.Paste")
			(net "SAS_EXP_A_PWR8")
		)
		(pad "3" smd rect
			(at -0.65024 -0.8255 270)
			(size 0.4064 1.2192)
			(layers "F.Cu" "F.Mask" "F.Paste")
			(net "GND")
		)
		(pad "4" smd rect
			(at -0.65024 0.8255 270)
			(size 0.4064 1.2192)
			(layers "F.Cu" "F.Mask" "F.Paste")
			(net "DRIVE_PWR8")
		)
		(pad "5" smd rect
			(at 0.65024 0.8255 270)
			(size 0.4064 1.2192)
			(layers "F.Cu" "F.Mask" "F.Paste")
			(net "P3V3")
		)
	)
)
